(kicad_pcb
	(version 20260206)
	(generator "pcbnew")
	(generator_version "10.0")
	(general
		(thickness 1.6)
		(legacy_teardrops no)
	)
	(paper "A4")
	(title_block
		(title "Bryce Canyon_IOM_M2_16342-2_OCP.brd")
		(comment 1 "Bryce Canyon / footprints 234-240 of 1146")
	)
	(layers
		(0 "F.Cu" signal "TOP")
		(4 "In1.Cu" signal "L2GND")
		(6 "In2.Cu" signal "L3")
		(8 "In3.Cu" signal "L4VCC")
		(10 "In4.Cu" signal "L5VCC")
		(12 "In5.Cu" signal "L6")
		(14 "In6.Cu" signal "L7GND")
		(2 "B.Cu" signal "BOTTOM")
		(9 "F.Adhes" user "F.Adhesive")
		(11 "B.Adhes" user "B.Adhesive")
		(13 "F.Paste" user "Package Geometry/Pastemask Top")
		(15 "B.Paste" user "Package Geometry/Pastemask Bottom")
		(5 "F.SilkS" user "Ref Des/Silkscreen Top")
		(7 "B.SilkS" user "Ref Des/Silkscreen Bottom")
		(1 "F.Mask" user "Board Geometry/Soldermask Top")
		(3 "B.Mask" user "Board Geometry/Soldermask Bottom")
		(17 "Dwgs.User" user "User.Drawings")
		(19 "Cmts.User" user "User.Comments")
		(21 "Eco1.User" user "User.Eco1")
		(23 "Eco2.User" user "User.Eco2")
		(25 "Edge.Cuts" user "Board Geometry/Outline")
		(27 "Margin" user)
		(31 "F.CrtYd" user "Package Geometry/Place Bound Top")
		(29 "B.CrtYd" user "Package Geometry/Place Bound Bottom")
		(35 "F.Fab" user "Ref Des/Assembly Top")
		(33 "B.Fab" user "Ref Des/Assembly Bottom")
	)
	(footprint ""
		(layer "F.Cu")
		(at 92.954094 -120.774714 90)
		(property "Reference" "R797"
			(at 0 0 90)
			(layer "F.SilkS")
			(hide yes)
			(effects
				(font
					(size 1.27 1.27)
				)
			)
		)
		(property "Value" "0R2J-2-GP"
			(at 0.064008 -3.993896 90)
			(unlocked yes)
			(layer "F.Fab")
			(hide yes)
			(effects
				(font
					(size 1.016 1.016)
					(thickness 0.1524)
				)
			)
		)
		(property "Device Type" "R402H16"
			(at 0.064008 -5.517896 90)
			(unlocked yes)
			(layer "F.Fab")
			(hide yes)
			(effects
				(font
					(size 1.016 1.016)
					(thickness 0.1524)
				)
			)
		)
		(duplicate_pad_numbers_are_jumpers no)
		(fp_line
			(start 0.508 -0.9398)
			(end -0.508 -0.9398)
			(stroke
				(width 0.1524)
				(type default)
			)
			(layer "F.SilkS")
		)
		(fp_line
			(start -0.508 -0.9398)
			(end -0.508 0.9398)
			(stroke
				(width 0.1524)
				(type default)
			)
			(layer "F.SilkS")
		)
		(fp_rect
			(start -0.508 0.9398)
			(end 0.508 -0.9398)
			(stroke
				(width 0)
				(type default)
			)
			(fill no)
			(layer "F.CrtYd")
		)
		(fp_rect
			(start -0.508 0.9398)
			(end 0.508 -0.9398)
			(stroke
				(width 0)
				(type default)
			)
			(fill no)
			(layer "F.Fab")
		)
		(pad "1" smd custom
			(at 0 -0.4445 90)
			(size 0.1397 0.1397)
			(layers "F.Cu" "F.Mask" "F.Paste")
			(net "UART_BMC_COMP_IN_RX")
			(options
				(clearance outline)
				(anchor circle)
			)
			(primitives
				(gr_poly
					(pts
						(arc
							(start -0.1778 -0.2794)
							(mid -0.249642 -0.249642)
							(end -0.2794 -0.1778)
						)
						(arc
							(start -0.2794 0.1778)
							(mid -0.249642 0.249642)
							(end -0.1778 0.2794)
						)
						(arc
							(start 0.1778 0.2794)
							(mid 0.249642 0.249642)
							(end 0.2794 0.1778)
						)
						(arc
							(start 0.2794 -0.1778)
							(mid 0.249642 -0.249642)
							(end 0.1778 -0.2794)
						)
					)
					(width 0)
					(fill yes)
				)
			)
		)
		(pad "2" smd custom
			(at 0 0.4445 90)
			(size 0.1397 0.1397)
			(layers "F.Cu" "F.Mask" "F.Paste")
			(net "UART_BMC_COMP_IN_RX_R")
			(options
				(clearance outline)
				(anchor circle)
			)
			(primitives
				(gr_poly
					(pts
						(arc
							(start -0.1778 -0.2794)
							(mid -0.249642 -0.249642)
							(end -0.2794 -0.1778)
						)
						(arc
							(start -0.2794 0.1778)
							(mid -0.249642 0.249642)
							(end -0.1778 0.2794)
						)
						(arc
							(start 0.1778 0.2794)
							(mid 0.249642 0.249642)
							(end 0.2794 0.1778)
						)
						(arc
							(start 0.2794 -0.1778)
							(mid 0.249642 -0.249642)
							(end 0.1778 -0.2794)
						)
					)
					(width 0)
					(fill yes)
				)
			)
		)
	)
	(footprint ""
		(layer "F.Cu")
		(at 30.506162 -155.909772 90)
		(property "Reference" "R331"
			(at 0 0 90)
			(layer "F.SilkS")
			(hide yes)
			(effects
				(font
					(size 1.27 1.27)
				)
			)
		)
		(property "Value" "4K7R2F-GP"
			(at 0.064008 -3.993896 90)
			(unlocked yes)
			(layer "F.Fab")
			(hide yes)
			(effects
				(font
					(size 1.016 1.016)
					(thickness 0.1524)
				)
			)
		)
		(property "Device Type" "R402H16"
			(at 0.064008 -5.517896 90)
			(unlocked yes)
			(layer "F.Fab")
			(hide yes)
			(effects
				(font
					(size 1.016 1.016)
					(thickness 0.1524)
				)
			)
		)
		(duplicate_pad_numbers_are_jumpers no)
		(fp_line
			(start 0.508 -0.9398)
			(end -0.508 -0.9398)
			(stroke
				(width 0.1524)
				(type default)
			)
			(layer "F.SilkS")
		)
		(fp_line
			(start -0.508 -0.9398)
			(end -0.508 0.9398)
			(stroke
				(width 0.1524)
				(type default)
			)
			(layer "F.SilkS")
		)
		(fp_rect
			(start -0.508 0.9398)
			(end 0.508 -0.9398)
			(stroke
				(width 0)
				(type default)
			)
			(fill no)
			(layer "F.CrtYd")
		)
		(fp_rect
			(start -0.508 0.9398)
			(end 0.508 -0.9398)
			(stroke
				(width 0)
				(type default)
			)
			(fill no)
			(layer "F.Fab")
		)
		(pad "1" smd custom
			(at 0 -0.4445 90)
			(size 0.1397 0.1397)
			(layers "F.Cu" "F.Mask" "F.Paste")
			(net "P3V3_STBY")
			(options
				(clearance outline)
				(anchor circle)
			)
			(primitives
				(gr_poly
					(pts
						(arc
							(start -0.1778 -0.2794)
							(mid -0.249642 -0.249642)
							(end -0.2794 -0.1778)
						)
						(arc
							(start -0.2794 0.1778)
							(mid -0.249642 0.249642)
							(end -0.1778 0.2794)
						)
						(arc
							(start 0.1778 0.2794)
							(mid 0.249642 0.249642)
							(end 0.2794 0.1778)
						)
						(arc
							(start 0.2794 -0.1778)
							(mid 0.249642 -0.249642)
							(end 0.1778 -0.2794)
						)
					)
					(width 0)
					(fill yes)
				)
			)
		)
		(pad "2" smd custom
			(at 0 0.4445 90)
			(size 0.1397 0.1397)
			(layers "F.Cu" "F.Mask" "F.Paste")
			(net "COMP_POWER_FAIL_N")
			(options
				(clearance outline)
				(anchor circle)
			)
			(primitives
				(gr_poly
					(pts
						(arc
							(start -0.1778 -0.2794)
							(mid -0.249642 -0.249642)
							(end -0.2794 -0.1778)
						)
						(arc
							(start -0.2794 0.1778)
							(mid -0.249642 0.249642)
							(end -0.1778 0.2794)
						)
						(arc
							(start 0.1778 0.2794)
							(mid 0.249642 0.249642)
							(end 0.2794 0.1778)
						)
						(arc
							(start 0.2794 -0.1778)
							(mid 0.249642 -0.249642)
							(end 0.1778 -0.2794)
						)
					)
					(width 0)
					(fill yes)
				)
			)
		)
	)
	(footprint ""
		(layer "F.Cu")
		(at 40.220646 -179.12461 180)
		(property "Reference" "R487"
			(at 0 0 180)
			(layer "F.SilkS")
			(hide yes)
			(effects
				(font
					(size 1.27 1.27)
				)
			)
		)
		(property "Value" "10KR2F-2-GP"
			(at 0.064008 -3.993896 180)
			(unlocked yes)
			(layer "F.Fab")
			(hide yes)
			(effects
				(font
					(size 1.016 1.016)
					(thickness 0.1524)
				)
			)
		)
		(property "Device Type" "R402H16"
			(at 0.064008 -5.517896 180)
			(unlocked yes)
			(layer "F.Fab")
			(hide yes)
			(effects
				(font
					(size 1.016 1.016)
					(thickness 0.1524)
				)
			)
		)
		(duplicate_pad_numbers_are_jumpers no)
		(fp_line
			(start 0.508 -0.9398)
			(end -0.508 -0.9398)
			(stroke
				(width 0.1524)
				(type default)
			)
			(layer "F.SilkS")
		)
		(fp_line
			(start -0.508 -0.9398)
			(end -0.508 0.9398)
			(stroke
				(width 0.1524)
				(type default)
			)
			(layer "F.SilkS")
		)
		(fp_rect
			(start -0.508 0.9398)
			(end 0.508 -0.9398)
			(stroke
				(width 0)
				(type default)
			)
			(fill no)
			(layer "F.CrtYd")
		)
		(fp_rect
			(start -0.508 0.9398)
			(end 0.508 -0.9398)
			(stroke
				(width 0)
				(type default)
			)
			(fill no)
			(layer "F.Fab")
		)
		(pad "1" smd custom
			(at 0 -0.4445 180)
			(size 0.1397 0.1397)
			(layers "F.Cu" "F.Mask" "F.Paste")
			(net "P3V3_STBY_VREG")
			(options
				(clearance outline)
				(anchor circle)
			)
			(primitives
				(gr_poly
					(pts
						(arc
							(start -0.1778 -0.2794)
							(mid -0.249642 -0.249642)
							(end -0.2794 -0.1778)
						)
						(arc
							(start -0.2794 0.1778)
							(mid -0.249642 0.249642)
							(end -0.1778 0.2794)
						)
						(arc
							(start 0.1778 0.2794)
							(mid 0.249642 0.249642)
							(end 0.2794 0.1778)
						)
						(arc
							(start 0.2794 -0.1778)
							(mid 0.249642 -0.249642)
							(end 0.1778 -0.2794)
						)
					)
					(width 0)
					(fill yes)
				)
			)
		)
		(pad "2" smd custom
			(at 0 0.4445 180)
			(size 0.1397 0.1397)
			(layers "F.Cu" "F.Mask" "F.Paste")
			(net "PWRGD_P3V3_STBY")
			(options
				(clearance outline)
				(anchor circle)
			)
			(primitives
				(gr_poly
					(pts
						(arc
							(start -0.1778 -0.2794)
							(mid -0.249642 -0.249642)
							(end -0.2794 -0.1778)
						)
						(arc
							(start -0.2794 0.1778)
							(mid -0.249642 0.249642)
							(end -0.1778 0.2794)
						)
						(arc
							(start 0.1778 0.2794)
							(mid 0.249642 0.249642)
							(end 0.2794 0.1778)
						)
						(arc
							(start 0.2794 -0.1778)
							(mid 0.249642 -0.249642)
							(end 0.1778 -0.2794)
						)
					)
					(width 0)
					(fill yes)
				)
			)
		)
	)
	(footprint ""
		(layer "F.Cu")
		(at 63.443358 -143.019272 90)
		(property "Reference" "R198"
			(at 0 0 90)
			(layer "F.SilkS")
			(hide yes)
			(effects
				(font
					(size 1.27 1.27)
				)
			)
		)
		(property "Value" "1KR2F-3-GP"
			(at 0.064008 -3.993896 90)
			(unlocked yes)
			(layer "F.Fab")
			(hide yes)
			(effects
				(font
					(size 1.016 1.016)
					(thickness 0.1524)
				)
			)
		)
		(property "Device Type" "R402H16"
			(at 0.064008 -5.517896 90)
			(unlocked yes)
			(layer "F.Fab")
			(hide yes)
			(effects
				(font
					(size 1.016 1.016)
					(thickness 0.1524)
				)
			)
		)
		(duplicate_pad_numbers_are_jumpers no)
		(fp_line
			(start 0.508 -0.9398)
			(end -0.508 -0.9398)
			(stroke
				(width 0.1524)
				(type default)
			)
			(layer "F.SilkS")
		)
		(fp_line
			(start -0.508 -0.9398)
			(end -0.508 0.9398)
			(stroke
				(width 0.1524)
				(type default)
			)
			(layer "F.SilkS")
		)
		(fp_rect
			(start -0.508 0.9398)
			(end 0.508 -0.9398)
			(stroke
				(width 0)
				(type default)
			)
			(fill no)
			(layer "F.CrtYd")
		)
		(fp_rect
			(start -0.508 0.9398)
			(end 0.508 -0.9398)
			(stroke
				(width 0)
				(type default)
			)
			(fill no)
			(layer "F.Fab")
		)
		(pad "1" smd custom
			(at 0 -0.4445 90)
			(size 0.1397 0.1397)
			(layers "F.Cu" "F.Mask" "F.Paste")
			(net "I2C_EXP_RMT_SCL_OUT")
			(options
				(clearance outline)
				(anchor circle)
			)
			(primitives
				(gr_poly
					(pts
						(arc
							(start -0.1778 -0.2794)
							(mid -0.249642 -0.249642)
							(end -0.2794 -0.1778)
						)
						(arc
							(start -0.2794 0.1778)
							(mid -0.249642 0.249642)
							(end -0.1778 0.2794)
						)
						(arc
							(start 0.1778 0.2794)
							(mid 0.249642 0.249642)
							(end 0.2794 0.1778)
						)
						(arc
							(start 0.2794 -0.1778)
							(mid 0.249642 -0.249642)
							(end 0.1778 -0.2794)
						)
					)
					(width 0)
					(fill yes)
				)
			)
		)
		(pad "2" smd custom
			(at 0 0.4445 90)
			(size 0.1397 0.1397)
			(layers "F.Cu" "F.Mask" "F.Paste")
			(net "P3V3_STBY")
			(options
				(clearance outline)
				(anchor circle)
			)
			(primitives
				(gr_poly
					(pts
						(arc
							(start -0.1778 -0.2794)
							(mid -0.249642 -0.249642)
							(end -0.2794 -0.1778)
						)
						(arc
							(start -0.2794 0.1778)
							(mid -0.249642 0.249642)
							(end -0.1778 0.2794)
						)
						(arc
							(start 0.1778 0.2794)
							(mid 0.249642 0.249642)
							(end 0.2794 0.1778)
						)
						(arc
							(start 0.2794 -0.1778)
							(mid 0.249642 -0.249642)
							(end 0.1778 -0.2794)
						)
					)
					(width 0)
					(fill yes)
				)
			)
		)
	)
	(footprint ""
		(layer "F.Cu")
		(at 215.80475 -45.587158 180)
		(property "Reference" "C162"
			(at 0 0 180)
			(layer "F.SilkS")
			(hide yes)
			(effects
				(font
					(size 1.27 1.27)
				)
			)
		)
		(property "Value" "SC1KP50V2KX-1GP"
			(at 1.1811 -2.7051 180)
			(unlocked yes)
			(layer "F.Fab")
			(hide yes)
			(effects
				(font
					(size 1.016 1.016)
					(thickness 0.1524)
				)
			)
		)
		(property "Device Type" "C402H22"
			(at 1.1811 -4.2291 180)
			(unlocked yes)
			(layer "F.Fab")
			(hide yes)
			(effects
				(font
					(size 1.016 1.016)
					(thickness 0.1524)
				)
			)
		)
		(duplicate_pad_numbers_are_jumpers no)
		(fp_rect
			(start -0.4318 0.9525)
			(end 0.4318 -0.9525)
			(stroke
				(width 0)
				(type default)
			)
			(fill no)
			(layer "F.CrtYd")
		)
		(fp_rect
			(start -0.4318 0.9525)
			(end 0.4318 -0.9525)
			(stroke
				(width 0)
				(type default)
			)
			(fill no)
			(layer "F.Fab")
		)
		(pad "1" smd custom
			(at 0 -0.4445 180)
			(size 0.1524 0.1524)
			(layers "F.Cu" "F.Mask" "F.Paste")
			(net "P5V_LL_R")
			(options
				(clearance outline)
				(anchor circle)
			)
			(primitives
				(gr_poly
					(pts
						(arc
							(start 0.3048 -0.2032)
							(mid 0.275042 -0.275042)
							(end 0.2032 -0.3048)
						)
						(arc
							(start -0.2032 -0.3048)
							(mid -0.275042 -0.275042)
							(end -0.3048 -0.2032)
						)
						(arc
							(start -0.3048 0.2032)
							(mid -0.275042 0.275042)
							(end -0.2032 0.3048)
						)
						(arc
							(start 0.2032 0.3048)
							(mid 0.275042 0.275042)
							(end 0.3048 0.2032)
						)
					)
					(width 0)
					(fill yes)
				)
			)
		)
		(pad "2" smd custom
			(at 0 0.4445 180)
			(size 0.1524 0.1524)
			(layers "F.Cu" "F.Mask" "F.Paste")
			(net "P5V_VFB")
			(options
				(clearance outline)
				(anchor circle)
			)
			(primitives
				(gr_poly
					(pts
						(arc
							(start 0.3048 -0.2032)
							(mid 0.275042 -0.275042)
							(end 0.2032 -0.3048)
						)
						(arc
							(start -0.2032 -0.3048)
							(mid -0.275042 -0.275042)
							(end -0.3048 -0.2032)
						)
						(arc
							(start -0.3048 0.2032)
							(mid -0.275042 0.275042)
							(end -0.2032 0.3048)
						)
						(arc
							(start 0.2032 0.3048)
							(mid 0.275042 0.275042)
							(end 0.3048 0.2032)
						)
					)
					(width 0)
					(fill yes)
				)
			)
		)
	)
	(footprint ""
		(layer "F.Cu")
		(at 77.283818 -86.954868 90)
		(property "Reference" "VIA6"
			(at 0 0 90)
			(layer "F.SilkS")
			(hide yes)
			(effects
				(font
					(size 1.27 1.27)
				)
			)
		)
		(property "Value" "85OHM-8L-1D6MM-L16L18-GP"
			(at 4.064 0.6096 90)
			(unlocked yes)
			(layer "F.Fab")
			(hide yes)
			(effects
				(font
					(size 1.016 1.016)
					(thickness 0.1524)
				)
			)
		)
		(property "Device Type" "VIA-PCIE-4P-368076"
			(at 4.064 -0.9144 90)
			(unlocked yes)
			(layer "F.Fab")
			(hide yes)
			(effects
				(font
					(size 1.016 1.016)
					(thickness 0.1524)
				)
			)
		)
		(duplicate_pad_numbers_are_jumpers no)
		(fp_rect
			(start -1.8415 0.381)
			(end 1.8415 -0.381)
			(stroke
				(width 0)
				(type default)
			)
			(fill no)
			(layer "F.CrtYd")
		)
		(fp_rect
			(start -1.8415 0.381)
			(end 1.8415 -0.381)
			(stroke
				(width 0)
				(type default)
			)
			(fill no)
			(layer "F.Fab")
		)
		(pad "1" thru_hole circle
			(at -1.4605 0 90)
			(size 0.508 0.508)
			(drill 0.254)
			(layers "*.Cu" "*.Mask")
			(remove_unused_layers no)
			(net "GND")
			(clearance 0.127)
			(thermal_gap 0.127)
		)
		(pad "2" thru_hole circle
			(at -0.4445 0 90)
			(size 0.508 0.508)
			(drill 0.254)
			(layers "*.Cu" "*.Mask")
			(remove_unused_layers no)
			(net "PCIE_COMP_TO_IOM_21_DP")
			(clearance 0.127)
			(thermal_gap 0.127)
		)
		(pad "3" thru_hole circle
			(at 0.4445 0 90)
			(size 0.508 0.508)
			(drill 0.254)
			(layers "*.Cu" "*.Mask")
			(remove_unused_layers no)
			(net "PCIE_COMP_TO_IOM_21_DN")
			(clearance 0.127)
			(thermal_gap 0.127)
		)
		(pad "4" thru_hole circle
			(at 1.4605 0 90)
			(size 0.508 0.508)
			(drill 0.254)
			(layers "*.Cu" "*.Mask")
			(remove_unused_layers no)
			(net "GND")
			(clearance 0.127)
			(thermal_gap 0.127)
		)
	)
	(footprint ""
		(layer "F.Cu")
		(at 19.880072 -15.68577)
		(property "Reference" "R48"
			(at 0 0 0)
			(layer "F.SilkS")
			(hide yes)
			(effects
				(font
					(size 1.27 1.27)
				)
			)
		)
		(property "Value" "4K7R2F-GP"
			(at 0.064008 -3.993896 0)
			(unlocked yes)
			(layer "F.Fab")
			(hide yes)
			(effects
				(font
					(size 1.016 1.016)
					(thickness 0.1524)
				)
			)
		)
		(property "Device Type" "R402H16"
			(at 0.064008 -5.517896 0)
			(unlocked yes)
			(layer "F.Fab")
			(hide yes)
			(effects
				(font
					(size 1.016 1.016)
					(thickness 0.1524)
				)
			)
		)
		(duplicate_pad_numbers_are_jumpers no)
		(fp_line
			(start -0.508 -0.9398)
			(end -0.508 0.9398)
			(stroke
				(width 0.1524)
				(type default)
			)
			(layer "F.SilkS")
		)
		(fp_line
			(start 0.508 -0.9398)
			(end -0.508 -0.9398)
			(stroke
				(width 0.1524)
				(type default)
			)
			(layer "F.SilkS")
		)
		(fp_rect
			(start -0.508 0.9398)
			(end 0.508 -0.9398)
			(stroke
				(width 0)
				(type default)
			)
			(fill no)
			(layer "F.CrtYd")
		)
		(fp_rect
			(start -0.508 0.9398)
			(end 0.508 -0.9398)
			(stroke
				(width 0)
				(type default)
			)
			(fill no)
			(layer "F.Fab")
		)
		(pad "1" smd custom
			(at 0 -0.4445)
			(size 0.1397 0.1397)
			(layers "F.Cu" "F.Mask" "F.Paste")
			(net "P3V3_STBY")
			(options
				(clearance outline)
				(anchor circle)
			)
			(primitives
				(gr_poly
					(pts
						(arc
							(start -0.1778 -0.2794)
							(mid -0.249642 -0.249642)
							(end -0.2794 -0.1778)
						)
						(arc
							(start -0.2794 0.1778)
							(mid -0.249642 0.249642)
							(end -0.1778 0.2794)
						)
						(arc
							(start 0.1778 0.2794)
							(mid 0.249642 0.249642)
							(end 0.2794 0.1778)
						)
						(arc
							(start 0.2794 -0.1778)
							(mid 0.249642 -0.249642)
							(end 0.1778 -0.2794)
						)
					)
					(width 0)
					(fill yes)
				)
			)
		)
		(pad "2" smd custom
			(at 0 0.4445)
			(size 0.1397 0.1397)
			(layers "F.Cu" "F.Mask" "F.Paste")
			(net "FP_PWR_BTN_N")
			(options
				(clearance outline)
				(anchor circle)
			)
			(primitives
				(gr_poly
					(pts
						(arc
							(start -0.1778 -0.2794)
							(mid -0.249642 -0.249642)
							(end -0.2794 -0.1778)
						)
						(arc
							(start -0.2794 0.1778)
							(mid -0.249642 0.249642)
							(end -0.1778 0.2794)
						)
						(arc
							(start 0.1778 0.2794)
							(mid 0.249642 0.249642)
							(end 0.2794 0.1778)
						)
						(arc
							(start 0.2794 -0.1778)
							(mid 0.249642 -0.249642)
							(end 0.1778 -0.2794)
						)
					)
					(width 0)
					(fill yes)
				)
			)
		)
	)
)
